# BASEBOARD_FAB2 (Tioga Pass) — schematic netlist excerpt (pin names and nets, part order shuffled) for the footprints in the layout excerpt that follows; sources: Cadence DE-HDL packaged netlist, KiCad conversion of Wiwynn_Tioga_Pass_MB.brd

CF23  SC22P50V2JN-4GP  5%  pkg SMD-BCG  page 235 : \1\ = VR_PVNN_PCH_AIREF1 ; \2\ = ISENSE_PVNN_PCH_PH1_IMON
C8W5  CAP_A  1.0UF 6.3V 10% X6S  pkg 0402V  page 245 : A = P3V3_STBY ; B = GND
C5M9  CAP_A  47UF 4V 20% X5R  pkg 0603V  page 220 : A = PVDDQ_DEF ; B = GND

(kicad_pcb
	(version 20260206)
	(generator "pcbnew")
	(generator_version "10.0")
	(general
		(thickness 1.6)
		(legacy_teardrops no)
	)
	(paper "A4")
	(title_block
		(title "Wiwynn_Tioga_Pass_MB.brd")
		(comment 1 "Tioga Pass / footprints 2879-2881 of 4770")
	)
	(layers
		(0 "F.Cu" signal "TOP")
		(4 "In1.Cu" signal "L2GND")
		(6 "In2.Cu" signal "L3")
		(8 "In3.Cu" signal "L4GND")
		(10 "In4.Cu" signal "L5")
		(12 "In5.Cu" signal "L6GND")
		(14 "In6.Cu" signal "L7VCC")
		(16 "In7.Cu" signal "L8VCC")
		(18 "In8.Cu" signal "L9GND")
		(20 "In9.Cu" signal "L10")
		(22 "In10.Cu" signal "L11GND")
		(24 "In11.Cu" signal "L12")
		(26 "In12.Cu" signal "L13GND")
		(2 "B.Cu" signal "BOTTOM")
		(9 "F.Adhes" user "F.Adhesive")
		(11 "B.Adhes" user "B.Adhesive")
		(13 "F.Paste" user "Package Geometry/Pastemask Top")
		(15 "B.Paste" user "Package Geometry/Pastemask Bottom")
		(5 "F.SilkS" user "Ref Des/Silkscreen Top")
		(7 "B.SilkS" user "Ref Des/Silkscreen Bottom")
		(1 "F.Mask" user "Board Geometry/Soldermask Top")
		(3 "B.Mask" user "Board Geometry/Soldermask Bottom")
		(17 "Dwgs.User" user "User.Drawings")
		(19 "Cmts.User" user "User.Comments")
		(21 "Eco1.User" user "User.Eco1")
		(23 "Eco2.User" user "User.Eco2")
		(25 "Edge.Cuts" user "Board Geometry/Outline")
		(27 "Margin" user)
		(31 "F.CrtYd" user "Package Geometry/Place Bound Top")
		(29 "B.CrtYd" user "Package Geometry/Place Bound Bottom")
		(35 "F.Fab" user "Ref Des/Assembly Top")
		(33 "B.Fab" user "Ref Des/Assembly Bottom")
	)
	(footprint ""
		(layer "B.Cu")
		(at 258.318 -135.3312 -90)
		(property "Reference" "C5M9"
			(at 0 0 90)
			(layer "B.SilkS")
			(hide yes)
			(effects
				(font
					(size 1.27 1.27)
				)
				(justify mirror)
			)
		)
		(property "Value" ""
			(at 0 0 90)
			(layer "B.Fab")
			(effects
				(font
					(size 1.27 1.27)
				)
				(justify mirror)
			)
		)
		(duplicate_pad_numbers_are_jumpers no)
		(fp_rect
			(start 0.500126 1.598422)
			(end -0.500126 -0.201422)
			(stroke
				(width 0)
				(type default)
			)
			(fill no)
			(layer "B.CrtYd")
		)
		(fp_line
			(start -0.500126 1.598422)
			(end 0.500126 1.598422)
			(stroke
				(width 0.1)
				(type default)
			)
			(layer "B.Fab")
		)
		(fp_line
			(start 0.500126 1.598422)
			(end 0.500126 -0.201422)
			(stroke
				(width 0.1)
				(type default)
			)
			(layer "B.Fab")
		)
		(fp_line
			(start -0.500126 -0.201422)
			(end -0.500126 1.598422)
			(stroke
				(width 0.1)
				(type default)
			)
			(layer "B.Fab")
		)
		(fp_line
			(start 0.500126 -0.201422)
			(end -0.500126 -0.201422)
			(stroke
				(width 0.1)
				(type default)
			)
			(layer "B.Fab")
		)
		(pad "1" smd rect
			(at 0 0 180)
			(size 0.889 0.9906)
			(layers "B.Cu" "B.Mask" "B.Paste")
			(net "PVDDQ_DEF")
		)
		(pad "2" smd rect
			(at 0 1.397 180)
			(size 0.889 0.9906)
			(layers "B.Cu" "B.Mask" "B.Paste")
			(net "GND")
		)
		(zone
			(layer "B.Cu")
			(hatch none 0.5)
			(connect_pads
				(clearance 0)
			)
			(min_thickness 0.25)
			(keepout
				(tracks allowed)
				(vias not_allowed)
				(pads allowed)
				(copperpour not_allowed)
				(footprints allowed)
			)
			(placement
				(enabled no)
				(sheetname "")
			)
			(fill
				(thermal_gap 0.5)
				(thermal_bridge_width 0.5)
				(island_removal_mode 0)
			)
			(polygon
				(pts
					(xy 257.3655 -134.8359) (xy 257.8735 -134.8359) (xy 257.8735 -135.8265) (xy 257.3655 -135.8265)
				)
			)
		)
		(zone
			(layer "B.Cu")
			(hatch none 0.5)
			(connect_pads
				(clearance 0)
			)
			(min_thickness 0.25)
			(keepout
				(tracks not_allowed)
				(vias allowed)
				(pads allowed)
				(copperpour not_allowed)
				(footprints allowed)
			)
			(placement
				(enabled no)
				(sheetname "")
			)
			(fill
				(thermal_gap 0.5)
				(thermal_bridge_width 0.5)
				(island_removal_mode 0)
			)
			(polygon
				(pts
					(xy 257.3655 -134.8359) (xy 257.8735 -134.8359) (xy 257.8735 -135.8265) (xy 257.3655 -135.8265)
				)
			)
		)
	)
	(footprint ""
		(layer "B.Cu")
		(at 398.146778 -157.11297 -90)
		(property "Reference" "CF23"
			(at 0 0 90)
			(layer "B.SilkS")
			(hide yes)
			(effects
				(font
					(size 1.27 1.27)
				)
				(justify mirror)
			)
		)
		(property "Value" "*"
			(at -1.1811 -2.8194 270)
			(unlocked yes)
			(layer "B.Fab")
			(hide yes)
			(effects
				(font
					(size 1.27 1.016)
					(thickness 0.1524)
				)
				(justify mirror)
			)
		)
		(property "Device Type" "SC22P50V2JN-4GP_SMD-BCG-SC22P5A"
			(at -1.1811 -4.3434 270)
			(unlocked yes)
			(layer "B.Fab")
			(hide yes)
			(effects
				(font
					(size 1.27 1.016)
					(thickness 0.1524)
				)
				(justify mirror)
			)
		)
		(duplicate_pad_numbers_are_jumpers no)
		(fp_rect
			(start 0.4318 0.9525)
			(end -0.4318 -0.9525)
			(stroke
				(width 0)
				(type default)
			)
			(fill no)
			(layer "B.CrtYd")
		)
		(fp_rect
			(start 0.4318 0.9525)
			(end -0.4318 -0.9525)
			(stroke
				(width 0)
				(type default)
			)
			(fill no)
			(layer "B.Fab")
		)
		(pad "1" smd custom
			(at 0 -0.4445 90)
			(size 0.1524 0.1524)
			(layers "B.Cu" "B.Mask" "B.Paste")
			(net "VR_PVNN_PCH_AIREF1")
			(options
				(clearance outline)
				(anchor circle)
			)
			(primitives
				(gr_poly
					(pts
						(arc
							(start 0.3048 0.2032)
							(mid 0.275042 0.275042)
							(end 0.2032 0.3048)
						)
						(arc
							(start -0.2032 0.3048)
							(mid -0.275042 0.275042)
							(end -0.3048 0.2032)
						)
						(arc
							(start -0.3048 -0.2032)
							(mid -0.275042 -0.275042)
							(end -0.2032 -0.3048)
						)
						(arc
							(start 0.2032 -0.3048)
							(mid 0.275042 -0.275042)
							(end 0.3048 -0.2032)
						)
					)
					(width 0)
					(fill yes)
				)
			)
		)
		(pad "2" smd custom
			(at 0 0.4445 90)
			(size 0.1524 0.1524)
			(layers "B.Cu" "B.Mask" "B.Paste")
			(net "ISENSE_PVNN_PCH_PH1_IMON")
			(options
				(clearance outline)
				(anchor circle)
			)
			(primitives
				(gr_poly
					(pts
						(arc
							(start 0.3048 0.2032)
							(mid 0.275042 0.275042)
							(end 0.2032 0.3048)
						)
						(arc
							(start -0.2032 0.3048)
							(mid -0.275042 0.275042)
							(end -0.3048 0.2032)
						)
						(arc
							(start -0.3048 -0.2032)
							(mid -0.275042 -0.275042)
							(end -0.2032 -0.3048)
						)
						(arc
							(start 0.2032 -0.3048)
							(mid 0.275042 -0.275042)
							(end 0.3048 -0.2032)
						)
					)
					(width 0)
					(fill yes)
				)
			)
		)
	)
	(footprint ""
		(layer "B.Cu")
		(at 381.5842 -2.448814)
		(property "Reference" "C8W5"
			(at 0.8382 -0.67818 0)
			(unlocked yes)
			(layer "B.SilkS")
			(effects
				(font
					(size 0.4064 0.254)
					(thickness 0.1524)
				)
				(justify left mirror)
			)
		)
		(property "Value" ""
			(at 0 0 0)
			(layer "B.Fab")
			(effects
				(font
					(size 1.27 1.27)
				)
				(justify mirror)
			)
		)
		(duplicate_pad_numbers_are_jumpers no)
		(fp_poly
			(pts
				(xy -0.3048 -0.1016) (xy -0.3048 0.9906) (xy 0.3048 0.9906) (xy 0.3048 -0.1016)
			)
			(stroke
				(width 0)
				(type default)
			)
			(fill no)
			(layer "B.CrtYd")
		)
		(fp_line
			(start -0.3048 -0.1016)
			(end 0.3048 -0.1016)
			(stroke
				(width 0.1)
				(type default)
			)
			(layer "B.Fab")
		)
		(fp_line
			(start -0.3048 0.9906)
			(end -0.3048 -0.1016)
			(stroke
				(width 0.1)
				(type default)
			)
			(layer "B.Fab")
		)
		(fp_line
			(start 0.3048 -0.1016)
			(end 0.3048 0.9906)
			(stroke
				(width 0.1)
				(type default)
			)
			(layer "B.Fab")
		)
		(fp_line
			(start 0.3048 0.9906)
			(end -0.3048 0.9906)
			(stroke
				(width 0.1)
				(type default)
			)
			(layer "B.Fab")
		)
		(pad "1" smd rect
			(at 0 0 180)
			(size 0.508 0.508)
			(layers "B.Cu" "B.Mask" "B.Paste")
			(net "P3V3_STBY")
		)
		(pad "2" smd rect
			(at 0 0.889 180)
			(size 0.508 0.508)
			(layers "B.Cu" "B.Mask" "B.Paste")
			(net "GND")
		)
		(zone
			(layer "B.Cu")
			(hatch none 0.5)
			(connect_pads
				(clearance 0)
			)
			(min_thickness 0.25)
			(keepout
				(tracks allowed)
				(vias not_allowed)
				(pads allowed)
				(copperpour not_allowed)
				(footprints allowed)
			)
			(placement
				(enabled no)
				(sheetname "")
			)
			(fill
				(thermal_gap 0.5)
				(thermal_bridge_width 0.5)
				(island_removal_mode 0)
			)
			(polygon
				(pts
					(xy 381.8382 -2.194814) (xy 381.3302 -2.194814) (xy 381.3302 -1.813814) (xy 381.8382 -1.813814)
				)
			)
		)
		(zone
			(layer "B.Cu")
			(hatch none 0.5)
			(connect_pads
				(clearance 0)
			)
			(min_thickness 0.25)
			(keepout
				(tracks not_allowed)
				(vias allowed)
				(pads allowed)
				(copperpour not_allowed)
				(footprints allowed)
			)
			(placement
				(enabled no)
				(sheetname "")
			)
			(fill
				(thermal_gap 0.5)
				(thermal_bridge_width 0.5)
				(island_removal_mode 0)
			)
			(polygon
				(pts
					(xy 381.8382 -1.813814) (xy 381.3302 -1.813814) (xy 381.3302 -2.194814) (xy 381.8382 -2.194814)
				)
			)
		)
	)
)
